(kicad_pcb
	(version 20241229)
	(generator "pcbnew")
	(generator_version "9.0")
	(general
		(thickness 1.599998)
		(legacy_teardrops no)
	)
	(paper "A4")
	(title_block
		(title "Artix - Datacenter Secure Control Module (DC-SCM)")
		(date "2024-11-06")
		(rev "1.1.3")
		(comment 9 "footprints 472-477 of 544")
	)
	(layers
		(0 "F.Cu" signal)
		(4 "In1.Cu" signal)
		(6 "In2.Cu" signal)
		(8 "In3.Cu" signal)
		(10 "In4.Cu" signal)
		(12 "In5.Cu" signal)
		(14 "In6.Cu" signal)
		(2 "B.Cu" signal)
		(9 "F.Adhes" user "F.Adhesive")
		(11 "B.Adhes" user "B.Adhesive")
		(13 "F.Paste" user)
		(15 "B.Paste" user)
		(5 "F.SilkS" user "F.Silkscreen")
		(7 "B.SilkS" user "B.Silkscreen")
		(1 "F.Mask" user)
		(3 "B.Mask" user)
		(17 "Dwgs.User" user "User.Drawings")
		(19 "Cmts.User" user "User.Comments")
		(21 "Eco1.User" user "User.Eco1")
		(23 "Eco2.User" user "User.Eco2")
		(25 "Edge.Cuts" user)
		(27 "Margin" user)
		(31 "F.CrtYd" user "F.Courtyard")
		(29 "B.CrtYd" user "B.Courtyard")
		(35 "F.Fab" user)
		(33 "B.Fab" user)
	)
	(footprint "antmicro-footprints:C_0402_1005Metric"
		(layer "B.Cu")
		(at 111.175 117.675)
		(descr "Capacitor SMD 0402")
		(tags "capacitor SMD 0402")
		(property "Reference" "C115"
			(at 0.825 0.425 0)
			(layer "B.SilkS")
			(effects
				(font
					(size 0.7 0.7)
					(thickness 0.15)
				)
				(justify right bottom mirror)
			)
		)
		(property "Value" "C_470n_0402"
			(at 0 -1.4 0)
			(layer "B.Fab")
			(effects
				(font
					(size 0.7 0.7)
					(thickness 0.15)
				)
				(justify right bottom mirror)
			)
		)
		(property "Datasheet" "https://product.tdk.com/en/search/capacitor/ceramic/mlcc/info?part_no=C1005X5R1E474M050BB"
			(at 0 0 0)
			(layer "F.Fab")
			(hide yes)
			(effects
				(font
					(size 1.27 1.27)
					(thickness 0.15)
				)
			)
		)
		(property "Description" "SMD Multilayer Ceramic Capacitor, 0.47 µF, 25 V, 0402 [1005 Metric], ± 20%, X5R, C"
			(at 0 0 0)
			(layer "F.Fab")
			(hide yes)
			(effects
				(font
					(size 1.27 1.27)
					(thickness 0.15)
				)
			)
		)
		(property "Author" "Antmicro"
			(at 0 0 0)
			(layer "B.Fab")
			(hide yes)
			(effects
				(font
					(size 1 1)
					(thickness 0.15)
				)
				(justify mirror)
			)
		)
		(property "Dielectric" ""
			(at 0 0 0)
			(layer "B.Fab")
			(hide yes)
			(effects
				(font
					(size 1 1)
					(thickness 0.15)
				)
				(justify mirror)
			)
		)
		(property "License" "Apache-2.0"
			(at 0 0 0)
			(layer "B.Fab")
			(hide yes)
			(effects
				(font
					(size 1 1)
					(thickness 0.15)
				)
				(justify mirror)
			)
		)
		(property "MPN" "C1005X5R1E474M050BB"
			(at 0 0 0)
			(layer "B.Fab")
			(hide yes)
			(effects
				(font
					(size 1 1)
					(thickness 0.15)
				)
				(justify mirror)
			)
		)
		(property "Manufacturer" "TDK"
			(at 0 0 0)
			(layer "B.Fab")
			(hide yes)
			(effects
				(font
					(size 1 1)
					(thickness 0.15)
				)
				(justify mirror)
			)
		)
		(property "Val" "470n"
			(at 0 0 0)
			(layer "B.Fab")
			(hide yes)
			(effects
				(font
					(size 1 1)
					(thickness 0.15)
				)
				(justify mirror)
			)
		)
		(property "Voltage" ""
			(at 0 0 0)
			(layer "B.Fab")
			(hide yes)
			(effects
				(font
					(size 1 1)
					(thickness 0.15)
				)
				(justify mirror)
			)
		)
		(sheetname "/FPGA banks 34-35 & CFG/")
		(sheetfile "fpga-banks-34-25-cfg.kicad_sch")
		(attr smd)
		(fp_rect
			(start -0.925 0.47)
			(end 0.925 -0.47)
			(stroke
				(width 0.05)
				(type default)
			)
			(fill no)
			(layer "B.CrtYd")
		)
		(fp_line
			(start -0.494 -0.248)
			(end -0.494 0.25)
			(stroke
				(width 0.15)
				(type solid)
			)
			(layer "B.Fab")
		)
		(fp_line
			(start -0.494 0.25)
			(end 0.504 0.25)
			(stroke
				(width 0.15)
				(type solid)
			)
			(layer "B.Fab")
		)
		(fp_line
			(start 0.504 -0.248)
			(end -0.494 -0.248)
			(stroke
				(width 0.15)
				(type solid)
			)
			(layer "B.Fab")
		)
		(fp_line
			(start 0.504 0.25)
			(end 0.504 -0.248)
			(stroke
				(width 0.15)
				(type solid)
			)
			(layer "B.Fab")
		)
		(pad "1" smd roundrect
			(at -0.48 0)
			(size 0.59 0.64)
			(layers "B.Cu" "B.Mask" "B.Paste")
			(roundrect_rratio 0.25)
			(net 1 "GND")
			(pintype "passive")
		)
		(pad "2" smd roundrect
			(at 0.48 0)
			(size 0.59 0.64)
			(layers "B.Cu" "B.Mask" "B.Paste")
			(roundrect_rratio 0.25)
			(net 2 "VCC3V3")
			(pintype "passive")
		)
	)
	(footprint "antmicro-footprints:R_0402_1005Metric"
		(layer "B.Cu")
		(at 98.175 149.675 -90)
		(descr "Resistor SMD 0402")
		(tags "resistor SMD 0402")
		(property "Reference" "R55"
			(at 2.525 -0.425 90)
			(layer "B.SilkS")
			(effects
				(font
					(size 0.7 0.7)
					(thickness 0.15)
				)
				(justify left bottom mirror)
			)
		)
		(property "Value" "R_51R_0402"
			(at 0 -1.4 90)
			(layer "B.Fab")
			(effects
				(font
					(size 0.7 0.7)
					(thickness 0.15)
				)
				(justify left bottom mirror)
			)
		)
		(property "Datasheet" "https://www.bourns.com/docs/product-datasheets/cr.pdf"
			(at 0 0 270)
			(layer "F.Fab")
			(hide yes)
			(effects
				(font
					(size 1.27 1.27)
					(thickness 0.15)
				)
			)
		)
		(property "Description" "SMD Chip Resistor, 51 ohm, ± 1%, 63 mW, 0402 [1005 Metric], Thick Film, General Purpose"
			(at 0 0 270)
			(layer "F.Fab")
			(hide yes)
			(effects
				(font
					(size 1.27 1.27)
					(thickness 0.15)
				)
			)
		)
		(property "Author" "Antmicro"
			(at -51.5 247.85 0)
			(layer "B.Fab")
			(hide yes)
			(effects
				(font
					(size 1 1)
					(thickness 0.15)
				)
				(justify mirror)
			)
		)
		(property "License" "Apache-2.0"
			(at -51.5 247.85 0)
			(layer "B.Fab")
			(hide yes)
			(effects
				(font
					(size 1 1)
					(thickness 0.15)
				)
				(justify mirror)
			)
		)
		(property "MPN" "CR0402-FX-51R0GLF"
			(at -51.5 247.85 0)
			(layer "B.Fab")
			(hide yes)
			(effects
				(font
					(size 1 1)
					(thickness 0.15)
				)
				(justify mirror)
			)
		)
		(property "Manufacturer" "Bourns"
			(at -51.5 247.85 0)
			(layer "B.Fab")
			(hide yes)
			(effects
				(font
					(size 1 1)
					(thickness 0.15)
				)
				(justify mirror)
			)
		)
		(property "Tolerance" "1%"
			(at -51.5 247.85 0)
			(layer "B.Fab")
			(hide yes)
			(effects
				(font
					(size 1 1)
					(thickness 0.15)
				)
				(justify mirror)
			)
		)
		(property "Val" "51R"
			(at -51.5 247.85 0)
			(layer "B.Fab")
			(hide yes)
			(effects
				(font
					(size 1 1)
					(thickness 0.15)
				)
				(justify mirror)
			)
		)
		(sheetname "/DDR3/")
		(sheetfile "ddr3.kicad_sch")
		(attr smd exclude_from_pos_files exclude_from_bom dnp)
		(fp_rect
			(start -0.925 0.47)
			(end 0.925 -0.47)
			(stroke
				(width 0.05)
				(type default)
			)
			(fill no)
			(layer "B.CrtYd")
		)
		(fp_rect
			(start -0.5 0.25)
			(end 0.5 -0.25)
			(stroke
				(width 0.15)
				(type solid)
			)
			(fill no)
			(layer "B.Fab")
		)
		(pad "1" smd roundrect
			(at -0.48 0 270)
			(size 0.59 0.64)
			(layers "B.Cu" "B.Mask" "B.Paste")
			(roundrect_rratio 0.25)
			(net 166 "DDR3_CAS")
			(pintype "passive")
		)
		(pad "2" smd roundrect
			(at 0.48 0 270)
			(size 0.59 0.64)
			(layers "B.Cu" "B.Mask" "B.Paste")
			(roundrect_rratio 0.25)
			(net 143 "/DDR3/DDR3_VTT")
			(pintype "passive")
		)
	)
	(footprint "antmicro-footprints:R_0402_1005Metric"
		(layer "B.Cu")
		(at 99.075 146.375 90)
		(descr "Resistor SMD 0402")
		(tags "resistor SMD 0402")
		(property "Reference" "R56"
			(at 1.274 -8.675 90)
			(layer "B.SilkS")
			(effects
				(font
					(size 0.7 0.7)
					(thickness 0.15)
				)
				(justify right bottom mirror)
			)
		)
		(property "Value" "R_51R_0402"
			(at 0 -1.4 90)
			(layer "B.Fab")
			(effects
				(font
					(size 0.7 0.7)
					(thickness 0.15)
				)
				(justify right bottom mirror)
			)
		)
		(property "Datasheet" "https://www.bourns.com/docs/product-datasheets/cr.pdf"
			(at 0 0 90)
			(layer "F.Fab")
			(hide yes)
			(effects
				(font
					(size 1.27 1.27)
					(thickness 0.15)
				)
			)
		)
		(property "Description" "SMD Chip Resistor, 51 ohm, ± 1%, 63 mW, 0402 [1005 Metric], Thick Film, General Purpose"
			(at 0 0 90)
			(layer "F.Fab")
			(hide yes)
			(effects
				(font
					(size 1.27 1.27)
					(thickness 0.15)
				)
			)
		)
		(property "Author" "Antmicro"
			(at 245.45 47.3 0)
			(layer "B.Fab")
			(hide yes)
			(effects
				(font
					(size 1 1)
					(thickness 0.15)
				)
				(justify mirror)
			)
		)
		(property "License" "Apache-2.0"
			(at 245.45 47.3 0)
			(layer "B.Fab")
			(hide yes)
			(effects
				(font
					(size 1 1)
					(thickness 0.15)
				)
				(justify mirror)
			)
		)
		(property "MPN" "CR0402-FX-51R0GLF"
			(at 245.45 47.3 0)
			(layer "B.Fab")
			(hide yes)
			(effects
				(font
					(size 1 1)
					(thickness 0.15)
				)
				(justify mirror)
			)
		)
		(property "Manufacturer" "Bourns"
			(at 245.45 47.3 0)
			(layer "B.Fab")
			(hide yes)
			(effects
				(font
					(size 1 1)
					(thickness 0.15)
				)
				(justify mirror)
			)
		)
		(property "Tolerance" "1%"
			(at 245.45 47.3 0)
			(layer "B.Fab")
			(hide yes)
			(effects
				(font
					(size 1 1)
					(thickness 0.15)
				)
				(justify mirror)
			)
		)
		(property "Val" "51R"
			(at 245.45 47.3 0)
			(layer "B.Fab")
			(hide yes)
			(effects
				(font
					(size 1 1)
					(thickness 0.15)
				)
				(justify mirror)
			)
		)
		(sheetname "/DDR3/")
		(sheetfile "ddr3.kicad_sch")
		(attr smd exclude_from_pos_files exclude_from_bom dnp)
		(fp_rect
			(start -0.925 0.47)
			(end 0.925 -0.47)
			(stroke
				(width 0.05)
				(type default)
			)
			(fill no)
			(layer "B.CrtYd")
		)
		(fp_rect
			(start -0.5 0.25)
			(end 0.5 -0.25)
			(stroke
				(width 0.15)
				(type solid)
			)
			(fill no)
			(layer "B.Fab")
		)
		(pad "1" smd roundrect
			(at -0.48 0 90)
			(size 0.59 0.64)
			(layers "B.Cu" "B.Mask" "B.Paste")
			(roundrect_rratio 0.25)
			(net 161 "DDR3_ODT")
			(pintype "passive")
		)
		(pad "2" smd roundrect
			(at 0.48 0 90)
			(size 0.59 0.64)
			(layers "B.Cu" "B.Mask" "B.Paste")
			(roundrect_rratio 0.25)
			(net 143 "/DDR3/DDR3_VTT")
			(pintype "passive")
		)
	)
	(footprint "antmicro-footprints:R_0402_1005Metric"
		(layer "B.Cu")
		(at 99.175 149.675 -90)
		(descr "Resistor SMD 0402")
		(tags "resistor SMD 0402")
		(property "Reference" "R162"
			(at 2.525 -0.425 90)
			(layer "B.SilkS")
			(effects
				(font
					(size 0.7 0.7)
					(thickness 0.15)
				)
				(justify left bottom mirror)
			)
		)
		(property "Value" "R_51R_0402"
			(at 0 -1.4 90)
			(layer "B.Fab")
			(effects
				(font
					(size 0.7 0.7)
					(thickness 0.15)
				)
				(justify left bottom mirror)
			)
		)
		(property "Datasheet" "https://www.bourns.com/docs/product-datasheets/cr.pdf"
			(at 0 0 270)
			(layer "F.Fab")
			(hide yes)
			(effects
				(font
					(size 1.27 1.27)
					(thickness 0.15)
				)
			)
		)
		(property "Description" "SMD Chip Resistor, 51 ohm, ± 1%, 63 mW, 0402 [1005 Metric], Thick Film, General Purpose"
			(at 0 0 270)
			(layer "F.Fab")
			(hide yes)
			(effects
				(font
					(size 1.27 1.27)
					(thickness 0.15)
				)
			)
		)
		(property "Author" "Antmicro"
			(at -50.5 248.85 0)
			(layer "B.Fab")
			(hide yes)
			(effects
				(font
					(size 1 1)
					(thickness 0.15)
				)
				(justify mirror)
			)
		)
		(property "License" "Apache-2.0"
			(at -50.5 248.85 0)
			(layer "B.Fab")
			(hide yes)
			(effects
				(font
					(size 1 1)
					(thickness 0.15)
				)
				(justify mirror)
			)
		)
		(property "MPN" "CR0402-FX-51R0GLF"
			(at -50.5 248.85 0)
			(layer "B.Fab")
			(hide yes)
			(effects
				(font
					(size 1 1)
					(thickness 0.15)
				)
				(justify mirror)
			)
		)
		(property "Manufacturer" "Bourns"
			(at -50.5 248.85 0)
			(layer "B.Fab")
			(hide yes)
			(effects
				(font
					(size 1 1)
					(thickness 0.15)
				)
				(justify mirror)
			)
		)
		(property "Tolerance" "1%"
			(at -50.5 248.85 0)
			(layer "B.Fab")
			(hide yes)
			(effects
				(font
					(size 1 1)
					(thickness 0.15)
				)
				(justify mirror)
			)
		)
		(property "Val" "51R"
			(at -50.5 248.85 0)
			(layer "B.Fab")
			(hide yes)
			(effects
				(font
					(size 1 1)
					(thickness 0.15)
				)
				(justify mirror)
			)
		)
		(sheetname "/DDR3/")
		(sheetfile "ddr3.kicad_sch")
		(attr smd exclude_from_pos_files exclude_from_bom dnp)
		(fp_rect
			(start -0.925 0.47)
			(end 0.925 -0.47)
			(stroke
				(width 0.05)
				(type default)
			)
			(fill no)
			(layer "B.CrtYd")
		)
		(fp_rect
			(start -0.5 0.25)
			(end 0.5 -0.25)
			(stroke
				(width 0.15)
				(type solid)
			)
			(fill no)
			(layer "B.Fab")
		)
		(pad "1" smd roundrect
			(at -0.48 0 270)
			(size 0.59 0.64)
			(layers "B.Cu" "B.Mask" "B.Paste")
			(roundrect_rratio 0.25)
			(net 153 "DDR3_WE")
			(pintype "passive")
		)
		(pad "2" smd roundrect
			(at 0.48 0 270)
			(size 0.59 0.64)
			(layers "B.Cu" "B.Mask" "B.Paste")
			(roundrect_rratio 0.25)
			(net 143 "/DDR3/DDR3_VTT")
			(pintype "passive")
		)
	)
	(footprint "antmicro-footprints:R_0402_1005Metric"
		(layer "B.Cu")
		(at 100.075 146.375 90)
		(descr "Resistor SMD 0402")
		(tags "resistor SMD 0402")
		(property "Reference" "R163"
			(at 1.274 -8.675 90)
			(layer "B.SilkS")
			(effects
				(font
					(size 0.7 0.7)
					(thickness 0.15)
				)
				(justify right bottom mirror)
			)
		)
		(property "Value" "R_51R_0402"
			(at 0 -1.4 90)
			(layer "B.Fab")
			(effects
				(font
					(size 0.7 0.7)
					(thickness 0.15)
				)
				(justify right bottom mirror)
			)
		)
		(property "Datasheet" "https://www.bourns.com/docs/product-datasheets/cr.pdf"
			(at 0 0 90)
			(layer "F.Fab")
			(hide yes)
			(effects
				(font
					(size 1.27 1.27)
					(thickness 0.15)
				)
			)
		)
		(property "Description" "SMD Chip Resistor, 51 ohm, ± 1%, 63 mW, 0402 [1005 Metric], Thick Film, General Purpose"
			(at 0 0 90)
			(layer "F.Fab")
			(hide yes)
			(effects
				(font
					(size 1.27 1.27)
					(thickness 0.15)
				)
			)
		)
		(property "Author" "Antmicro"
			(at 246.45 46.3 0)
			(layer "B.Fab")
			(hide yes)
			(effects
				(font
					(size 1 1)
					(thickness 0.15)
				)
				(justify mirror)
			)
		)
		(property "License" "Apache-2.0"
			(at 246.45 46.3 0)
			(layer "B.Fab")
			(hide yes)
			(effects
				(font
					(size 1 1)
					(thickness 0.15)
				)
				(justify mirror)
			)
		)
		(property "MPN" "CR0402-FX-51R0GLF"
			(at 246.45 46.3 0)
			(layer "B.Fab")
			(hide yes)
			(effects
				(font
					(size 1 1)
					(thickness 0.15)
				)
				(justify mirror)
			)
		)
		(property "Manufacturer" "Bourns"
			(at 246.45 46.3 0)
			(layer "B.Fab")
			(hide yes)
			(effects
				(font
					(size 1 1)
					(thickness 0.15)
				)
				(justify mirror)
			)
		)
		(property "Tolerance" "1%"
			(at 246.45 46.3 0)
			(layer "B.Fab")
			(hide yes)
			(effects
				(font
					(size 1 1)
					(thickness 0.15)
				)
				(justify mirror)
			)
		)
		(property "Val" "51R"
			(at 246.45 46.3 0)
			(layer "B.Fab")
			(hide yes)
			(effects
				(font
					(size 1 1)
					(thickness 0.15)
				)
				(justify mirror)
			)
		)
		(sheetname "/DDR3/")
		(sheetfile "ddr3.kicad_sch")
		(attr smd exclude_from_pos_files exclude_from_bom dnp)
		(fp_rect
			(start -0.925 0.47)
			(end 0.925 -0.47)
			(stroke
				(width 0.05)
				(type default)
			)
			(fill no)
			(layer "B.CrtYd")
		)
		(fp_rect
			(start -0.5 0.25)
			(end 0.5 -0.25)
			(stroke
				(width 0.15)
				(type solid)
			)
			(fill no)
			(layer "B.Fab")
		)
		(pad "1" smd roundrect
			(at -0.48 0 90)
			(size 0.59 0.64)
			(layers "B.Cu" "B.Mask" "B.Paste")
			(roundrect_rratio 0.25)
			(net 164 "DDR3_BA0")
			(pintype "passive")
		)
		(pad "2" smd roundrect
			(at 0.48 0 90)
			(size 0.59 0.64)
			(layers "B.Cu" "B.Mask" "B.Paste")
			(roundrect_rratio 0.25)
			(net 143 "/DDR3/DDR3_VTT")
			(pintype "passive")
		)
	)
	(footprint "antmicro-footprints:R_0402_1005Metric"
		(layer "B.Cu")
		(at 100.175 149.675 -90)
		(descr "Resistor SMD 0402")
		(tags "resistor SMD 0402")
		(property "Reference" "R164"
			(at 2.525 -0.425 90)
			(layer "B.SilkS")
			(effects
				(font
					(size 0.7 0.7)
					(thickness 0.15)
				)
				(justify left bottom mirror)
			)
		)
		(property "Value" "R_51R_0402"
			(at 0 -1.4 90)
			(layer "B.Fab")
			(effects
				(font
					(size 0.7 0.7)
					(thickness 0.15)
				)
				(justify left bottom mirror)
			)
		)
		(property "Datasheet" "https://www.bourns.com/docs/product-datasheets/cr.pdf"
			(at 0 0 270)
			(layer "F.Fab")
			(hide yes)
			(effects
				(font
					(size 1.27 1.27)
					(thickness 0.15)
				)
			)
		)
		(property "Description" "SMD Chip Resistor, 51 ohm, ± 1%, 63 mW, 0402 [1005 Metric], Thick Film, General Purpose"
			(at 0 0 270)
			(layer "F.Fab")
			(hide yes)
			(effects
				(font
					(size 1.27 1.27)
					(thickness 0.15)
				)
			)
		)
		(property "Author" "Antmicro"
			(at -49.5 249.85 0)
			(layer "B.Fab")
			(hide yes)
			(effects
				(font
					(size 1 1)
					(thickness 0.15)
				)
				(justify mirror)
			)
		)
		(property "License" "Apache-2.0"
			(at -49.5 249.85 0)
			(layer "B.Fab")
			(hide yes)
			(effects
				(font
					(size 1 1)
					(thickness 0.15)
				)
				(justify mirror)
			)
		)
		(property "MPN" "CR0402-FX-51R0GLF"
			(at -49.5 249.85 0)
			(layer "B.Fab")
			(hide yes)
			(effects
				(font
					(size 1 1)
					(thickness 0.15)
				)
				(justify mirror)
			)
		)
		(property "Manufacturer" "Bourns"
			(at -49.5 249.85 0)
			(layer "B.Fab")
			(hide yes)
			(effects
				(font
					(size 1 1)
					(thickness 0.15)
				)
				(justify mirror)
			)
		)
		(property "Tolerance" "1%"
			(at -49.5 249.85 0)
			(layer "B.Fab")
			(hide yes)
			(effects
				(font
					(size 1 1)
					(thickness 0.15)
				)
				(justify mirror)
			)
		)
		(property "Val" "51R"
			(at -49.5 249.85 0)
			(layer "B.Fab")
			(hide yes)
			(effects
				(font
					(size 1 1)
					(thickness 0.15)
				)
				(justify mirror)
			)
		)
		(sheetname "/DDR3/")
		(sheetfile "ddr3.kicad_sch")
		(attr smd exclude_from_pos_files exclude_from_bom dnp)
		(fp_rect
			(start -0.925 0.47)
			(end 0.925 -0.47)
			(stroke
				(width 0.05)
				(type default)
			)
			(fill no)
			(layer "B.CrtYd")
		)
		(fp_rect
			(start -0.5 0.25)
			(end 0.5 -0.25)
			(stroke
				(width 0.15)
				(type solid)
			)
			(fill no)
			(layer "B.Fab")
		)
		(pad "1" smd roundrect
			(at -0.48 0 270)
			(size 0.59 0.64)
			(layers "B.Cu" "B.Mask" "B.Paste")
			(roundrect_rratio 0.25)
			(net 152 "DDR3_BA2")
			(pintype "passive")
		)
		(pad "2" smd roundrect
			(at 0.48 0 270)
			(size 0.59 0.64)
			(layers "B.Cu" "B.Mask" "B.Paste")
			(roundrect_rratio 0.25)
			(net 143 "/DDR3/DDR3_VTT")
			(pintype "passive")
		)
	)
)
